# T6G (Grand Teton) — schematic parts with pin connectivity, parts 8074–8074 of 8303; source: Cadence DE-HDL packaged netlist (pstxprt.dat, pstxnet.dat, pstchip.dat)

U18  LCMXO3LF9400C5BG484C  LCMXO3LF-9400C-5BG484C IC  pkg BGA484_0-8_19X19_H67  page 82  (pins 1-334 of 484)
  A1  GND1  POWER  = GND
  A2  \pt9b||l_gpllc\  BI  = FM_I3C_CPU1_MUX0_R_SEL
  A3  PT10B  BI  = SCM_JTAG_MUX_R_S1
  A4  PT11B  BI  = SGPIO_SCM_DI_R<0>
  A5  PT12B  BI  = SGPIO_SCM_RESET_N
  A6  PT13B  BI  = E1S_0_PERST1_CLKREQ_R_N
  A7  PT14B  BI  = FM_UV_ADR_TRIGGER_R_N
  A8  PT20B  BI  = SGPIO_OCP_SFF_DATAOUT
  A9  PT21B  BI  = OCP_V3_1_P3V3_PLD_R_PWRGD
  A10  \pt23b||pclkc0_1\  BI  = OC_ALERT_N
  A11  PT24B  BI  = FM_BOARD_BMC_SKU_ID4
  A12  \pt27d||sda||pclkc0_0\  BI  = SMB_1_PLD_3V3AUX_SDA_R2
  A13  PT29A  BI  = SMB_2_PLD_3V3AUX_SCL_R2
  A14  PT30A  BI  = SGPIO_OCP_V3_2_LD_N
  A15  PT38A  BI  = SCM_SYS_PWROK
  A16  PT39A  BI  = PWRGD_P5V
  A17  PT40A  BI  = PWRGD_PVDDCR_SOC_P1
  A18  PT41A  BI  = FM_LED_PWRGD_PVDDIO_P1
  A19  PT42A  BI  = FM_LED_PWRGD_PVDD18_S5_P1
  A20  \pt43a||r_gpllt\  BI  = P1V8_RETIMER_CPU1_R_EN
  A21  \pt44a||r_gpllt\  BI  = SMB_BMC_SWB_EN
  A22  GND2  POWER  = GND
  AA1  PL29B  BI  = OCP_SFF_P3V3_P12V_ADC_ALERT
  AA2  PB5A  BI  = FM_SWB_PWR_EN
  AA3  \pb7a||csspin\  BI  = PRSNT_OCP_SFF_N
  AA4  PB8A  BI  = GPU_FPGA_EROT_RST_R_N
  AA5  PB10A  BI  = GPU_FPGA_EROT_RECOV_R_N
  AA6  PB11A  BI  = PWRGD_PVDD18_S5_R_P1
  AA7  PB13A  BI  = FM_PVDD11_S3_P1_EN
  AA8  PB18A  BI  = FM_PVDD18_S5_P0_EN
  AA9  PB19A  BI  = FM_PVDDIO_P1_EN
  AA10  \pb22a||pclkt2_0\  BI  = P0V9_RETIMER_CPU0_EN_R2
  AA11  PB24A  BI  = P12V_E1S_0_EN
  AA12  \pb29b||pclkc2_1\  BI  = GPU_3V3IO_RSVD3_ISO_R
  AA13  PB30B  BI  = RST_PERST_E1S_0_R_N
  AA14  PB33B  BI  = PRSNT_CABLE_GPU_A1_ISO_R_N
  AA15  PB35B  BI  = GPU_HMC_PRSNT_ISO_R_N
  AA16  PB38B  BI  = GPU_FPGA_EROT_FATALERR_ISO_R_N
  AA17  PB40B  BI  = FM_SMB_1_ALERT_GPU_ISO_R_N
  AA18  PB41B  BI  = FM_GPU_PWRGD_ISO_R
  AA19  PB43B  BI  = RST_PERST_OCP_V3_2_N
  AA20  PB44B  BI  = P12V_OCP_V3_2_EN_R
  AA21  \pb46b||si||sispi\  BI  = P0V9_RETIMER_CPU1_EN_R2
  AA22  PR29A  BI  = FM_CPU1_PWRGD_OUT
  AB1  GND51  POWER  = GND
  AB2  PB5B  BI  = GPU_NVS_PWR_BRAKE_R_N
  AB3  PB7B  BI  = PVDDCR_CPU0_P0_PMALERT
  AB4  PB8B  BI  = PRSNT_SWB_ISO_R_N
  AB5  PB10B  BI  = BMC_MONITER
  AB6  PB11B  BI  = FM_PWRGD_PVDD33_S5
  AB7  PB13B  BI  = FM_PWRGD_PVDD11_S3_P1
  AB8  PB18B  BI  = FM_PWRGD_PVDD18_S5_P0
  AB9  PB19B  BI  = FM_PWRGD_PVDDIO_P1
  AB10  \pb22b||pclkc2_0\  BI  = BMC_FPGA_LED1
  AB11  PB24B  BI  = FM_LED_PWRGD_PVDD18_S5_P0
  AB12  \pb29a||pclkt2_1\  BI  = GPU_3V3IO_RSVD1_ISO_R
  AB13  PB30A  BI  = FM_RST_PERST_SCM_R_N
  AB14  PB33A  BI  = GPU_3V3IO_RSVD5_FFU_ISO_R
  AB15  PB35A  BI  = GPU_BASE_HMC_READY_ISO_R
  AB16  PB38A  BI  = GPU_PRSNT_N_ISO_R
  AB17  PB40A  BI  = FM_SWB_BIC_READY_ISO_R_N
  AB18  PB41A  BI  = FM_SWB_PWRGD_ISO_R
  AB19  PB43A  BI  = GPU_FPGA_READY_ISO_R
  AB20  PB44A  BI  = PRSNT_HDT_N
  AB21  \pb46a||sn\  BI  = PU_SPI_PLD_CS_N
  AB22  GND52  POWER  = GND
  B1  \pt9a||l_gpllt\  BI  = FM_I3C_CPU0_MUX0_OE_R_N
  B2  PT10A  BI  = FM_I3C_CPU1_MUX0_OE_R_N
  B3  PT11A  BI  = SCM_JTAG_MUX_R_S0
  B4  PT12A  BI  = SGPIO_SCM_DO_<1>
  B5  PT13A  BI  = SGPIO_SCM_LD_<1>
  B6  PT14A  BI  = IRQ_HSC_FAULT_BUF_R_N
  B7  GND3  POWER  = GND
  B8  PT20A  BI  = SGPIO_OCP_SFF_DATAIN
  B9  PT21A  BI  = P3V3_OCP_SFF_EN
  B10  \pt23a||pclkt0_1\  BI  = UV_ALERT_N
  B11  PT24A  BI  = FM_BOARD_BMC_SKU_ID3
  B12  \pt27c||scl||pclkt0_0\  BI  = SMB_1_PLD_3V3AUX_SCL_R2
  B13  PT29B  BI  = SMB_2_PLD_3V3AUX_SDA_R2
  B14  PT30B  BI  = SGPIO_OCP_V3_2_DATAIN
  B15  PT38B  BI  = P1V8_RETIMER_CPU0_R_EN
  B16  GND4  POWER  = GND
  B17  PT39B  BI  = PVDDCR_CPU0_P0_EN
  B18  PT40B  BI  = FM_LED_PWRGD_PVDDCR_SOC_P1
  B19  PT41B  BI  = FM_LED_PWRGD_PVDD11_S3_P1
  B20  PT42B  BI  = FM_SOL_UART_CH_SEL
  B21  \pt43b||r_gpllc\  BI  = IRQ_SML1_PMBUS_ALERT_N
  B22  \pt44b||r_gpllc\  BI  = FM_OCP_V3_2_PWR_GOOD
  C1  \pl4a||l_gpllt_in\  BI  = FM_CPU0_XTRIG_L5
  C2  GND5  POWER  = GND
  C3  PT10C  BI  = FM_I3C_CPU0_MUX0_R_SEL
  C4  PT10D  BI  = FM_I3C_CPU0_MUX1_OE_R_N
  C5  PT12D  BI  = FM_BOARD_BMC_SKU_ID0
  C6  PT14C  BI  = SGPIO_SCM_DI_R<1>
  C7  VCCIO0_1  POWER  = P3V3_AUX
  C8  PT15A  BI  = PCIE_M2_SSD0_PRSNT_N
  C9  PT20C  BI  = SGPIO_OCP_SFF_CLK
  C10  \pt22d||tms\  BI  = JTAG_SCM_PLD_TMS
  C11  GND6  POWER  = GND
  C12  VCCIO0_2  POWER  = P3V3_AUX
  C13  PT29C  BI  = SCM_ROT_CPU_RST_R_N
  C14  PT30C  BI  = SGPIO_OCP_V3_2_DATAOUT
  C15  PT38C  BI  = PVDDCR_SOC_P1_EN
  C16  VCCIO0_3  POWER  = P3V3_AUX
  C17  PT39C  BI  = RST_SRST_PLD_BMC_R_N
  C18  PT41C  BI  = FM_OCP_V3_2_AUX_PWR_EN
  C19  PT43C  BI  = CLK_GEN2_BMC_RC_OE_R_N
  C20  PT43D  BI  = CLK_GEN2_GPU_FPGA_OE_R_N
  C21  \pr2a||r_gpllt_fb\  BI  = FM_CPU0_SLP_S5_N
  C22  \pr2b||r_gpllc_fb\  BI  = FM_CPU0_SLP_S3_N
  D1  PL5A  BI  = FM_SMM_CRASHDUMP_R
  D2  \pl4b||l_gpllc_in\  BI  = FM_CPU0_XTRIG_L4
  D3  PL2A  BI  = FM_CPU1_XTRIG_L4
  D4  PL2B  BI  = FM_CPU1_XTRIG_L5
  D5  PT12C  BI  = FM_I3C_CPU1_MUX1_R_SEL
  D6  PT13C  BI  = SGPIO_SCM_CLK_<0>
  D7  PT14D  BI  = SGPIO_SCM_LD_<0>
  D8  PT15B  BI  = SGPIO_OCP_SFF_LD_N
  D9  PT20D  BI  = OCP_V3_2_MAIN_PWR_EN
  D10  \pt22c||tck\  BI  = JTAG_SCM_PLD_TCK
  D11  PT24D  BI  = JTAG_SCM_TRST_R_N
  D12  PT27A  BI  = FM_FAN_PWR_EN
  D13  PT29D  BI  = RST_MB_STBY_N
  D14  PT30D  BI  = SGPIO_OCP_V3_2_CLK
  D15  PT38D  BI  = PRSNT_OCP_V3_2_N
  D16  PT39D  BI  = FPGA_IO3V3_RSVD_1
  D17  PT40D  BI  = RST_SMB_SWITCH_N
  D18  PT41D  BI  = SGPIO_SCM_CLK_<1>
  D19  PR3C  BI  = PWRGD_P0V9_RETIMER_CPU0_R2
  D20  PR3D  BI  = RST_CPU0_PERST1_R_N
  D21  \pr3b||r_gpllc_in\  BI  = FM_CPU1_SLP_S3_N
  D22  \pr3a||r_gpllt_in\  BI  = FM_CPU1_SLP_S5_N
  E1  PL6A  BI  = FM_BMC_TPM_PRES_N_R
  E2  PL5B  BI  = FM_CPU1_BMC_RST_R_N
  E3  PL5C  BI  = FM_CPU0_XTRIG_L7
  E4  \pl3a||l_gpllt_fb\  BI  = FM_CPU0_XTRIG_L6
  E5  GND7  POWER  = GND
  E6  PT9C  BI  = FM_I3C_CPU1_MUX1_OE_R_N
  E7  PT13D  BI  = SGPIO_SCM_DO_<0>
  E8  \pt15c||tdo\  BI  = JTAG_SCM_PLD_TDI
  E9  \pt15d||tdi\  BI  = JTAG_SCM_PLD_TDO
  E10  PT22B  BI  = FM_LED_ACTIVE_E1S_0
  E11  PT24C  BI  = FM_SYS_THROTTLE_R_N
  E12  PT27B  BI  = SCM_SYS_PWRBTN_N
  E13  PT28C  BI  = HP_LVC3_OCP_V3_2_P12V_PWRGD_R
  E14  \pt31c||jtagenb\  BI  = CPLD_JTAG_EN
  E15  \pt31d||programn\  BI  = CPLD_PROGRAMN
  E16  PT40C  BI  = FM_LED_PWRGD_PVDDCR_CPU1_P1
  E17  \pt44d||done\  BI  = VIRTUAL_RESEAT_FPGA_R_N
  E18  GND8  POWER  = GND
  E19  PR4C  BI  = RST_CPU1_PERST0_R_N
  E20  PR4D  BI  = PWRGD_P0V9_RETIMER_CPU1_R2
  E21  PR4B  BI  = RST_RT_CPU1_P0_RESET_R2_N
  E22  PR4A  BI  = RST_RT_CPU1_P0_PERST_R2_N
  F1  PL6B  BI  = FM_PVDDCR_CPU0_P0_OCP_N
  F2  GND9  POWER  = GND
  F3  VCCIO5_1  POWER  = P1V8_AUX
  F4  PL5D  BI  = FM_BMC_READY_R_N
  F5  \pl3b||l_gpllc_fb\  BI  = IRQ_BMC_SMI_R_N
  F6  PL2C  BI  = FM_CPU1_XTRIG_L6
  F7  PT9D  BI  = FM_I3C_CPU0_MUX1_R_SEL
  F8  PT11C  BI  = PWRGD_PS_PWROK_PLD_ISO_R
  F9  PT21C  BI  = P12V_OCP_SFF_EN
  F10  PT22A  BI  = FM_BOARD_BMC_SKU_ID2
  F11  PT23D  BI  = SMB_CPU0_4_XLTR_R_SDA
  F12  PT28B  BI  = GPU_3V3IO_RSVD3_FFU_ISO_R
  F13  PT28D  BI  = FM_UARTSW_MSB_N
  F14  PT31B  BI  = SCM_SPARE_1
  F15  PT42C  BI  = OCP_V3_2_P3V3_PLD_R_PWRGD
  F16  \pt44c||initn\  BI  = VIRTUAL_RESEAT
  F17  PR2C  BI  = RST_CPU0_PERST0_R_N
  F18  PR5C  BI  = TP_SLOT1_CLKREQ_0_R_N
  F19  PR5D  BI  = FM_CPU0_SYS_RESET_N
  F20  VCCIO1_1  POWER  = P1V8_AUX
  F21  GND10  POWER  = GND
  F22  PR5A  BI  = FM_CPU1_RSMRST_N
  G1  \pl7b||pclkc5_0\  BI  = FM_CPU1_PROCHOT_R_N
  G2  \pl7a||pclkt5_0\  BI  = FM_PVDDCR_CPU0_P1_OCP_N
  G3  PL6C  BI  = FM_PVDDCR_CPU1_P0_OCP_N
  G4  PL6D  BI  = FM_PVDDCR_CPU1_P1_OCP_N
  G5  PL4C  BI  = IRQ_SMI_ACTIVE_N_R
  G6  PL3C  BI  = FM_CPU1_XTRIG_L7
  G7  PL2D  BI  = FM_CPU1_SA1
  G8  PT11D  BI  = SGPIO_SCM_INTR_R_N
  G9  PT21D  BI  = FM_BOARD_BMC_SKU_ID1
  G10  VCCIO0_4  POWER  = P3V3_AUX
  G11  PT23C  BI  = SMB_CPU0_4_XLTR_R_SCL
  G12  PT28A  BI  = PRSNT_CABLE_GPU_B3_ISO_R_N
  G13  VCCIO0_5  POWER  = P3V3_AUX
  G14  PT31A  BI  = SCM_SPARE_0
  G15  PT42D  BI  = FM_UARTSW_LSB_N
  G16  PR2D  BI  = RST_CPU1_PERST1_R_N
  G17  PR7C  BI  = RST_CPU0_KBRST_N
  G18  PR6D  BI  = RST_RT_CPU1_P1_RESET_R2_N
  G19  PR6C  BI  = RST_RT_CPU1_P1_PERST_R2_N
  G20  PR6B  BI  = FM_CPU0_NV_SAVE_N
  G21  PR6A  BI  = FM_CPU1_SYS_RESET_N
  G22  PR5B  BI  = FM_CPU0_RSMRST_N
  H1  PL10B  BI  = RT_BOARD_ID_ID1
  H2  PL10A  BI  = CPU0_THERMTRIP_R_N
  H3  PL7D  BI  = FM_PVDD11_S3_P0_OCP_N
  H4  PL7C  BI  = FM_PVDD11_S3_P1_OCP_N
  H5  PL11A  BI  = FM_CPU0_SA0
  H6  PL4D  BI  = IRQ_TPM_SPI_R1_N
  H7  PL3D  BI  = IRQ_CPU_BMC_NMI_R_N
  H8  GND11  POWER  = GND
  H9  VCCIO0_6  POWER  = P3V3_AUX
  H10  GND12  POWER  = GND
  H11  VCCIO0_7  POWER  = P3V3_AUX
  H12  VCCIO0_8  POWER  = P3V3_AUX
  H13  GND13  POWER  = GND
  H14  VCCIO0_9  POWER  = P3V3_AUX
  H15  GND14  POWER  = GND
  H16  PR10D  BI  = PVDD11_S3_P1_RESET_N
  H17  PR10C  BI  = PVDD11_S3_P0_RESET_N
  H18  PR10B  BI  = FM_CPU1_NV_SAVE_N
  H19  PR10A  BI  = FM_PWRGD_CPU0_PWROK
  H20  PR7D  BI  = CPU0_JTAG_BUF_R_OE
  H21  PR7B  BI  = FM_RST_CPU1_RESETL_N
  H22  PR7A  BI  = FM_RST_CPU0_RESETL_N
  J1  PL12B  BI  = FAB_BMC_REV_ID0
  J2  PL12A  BI  = FM_CPU0_SA1
  J3  PL11D  BI  = FM_INT_CPU0_HP_UBM_R_N
  J4  PL11C  BI  = RT_BOARD_ID_ID0
  J5  PL11B  BI  = CPU1_THERMTRIP_R_N
  J6  PL10D  BI  = FM_CPU0_PROCHOT_R_N
  J7  PL10C  BI  = FM_CPU1_SA0
  J8  VCCIO5_2  POWER  = P1V8_AUX
  J9  GND15  POWER  = GND
  J10  GND16  POWER  = GND
  J11  GND17  POWER  = GND
  J12  GND18  POWER  = GND
  J13  GND19  POWER  = GND
  J14  GND20  POWER  = GND
  J15  VCCIO1_2  POWER  = P1V8_AUX
  J16  PR11A  BI  = FM_CPU0_NMI_SYNC_FLOOD_N
  J17  PR11B  BI  = FM_FPGA_DEBUG_LED_CTRL
  J18  PR11C  BI  = FM_PWRGD_CPU1_PWROK
  J19  PR11D  BI  = FM_P1_PCC0_R_N
  J20  PR12C  BI  = FM_P1_PCC1_R_N
  J21  PR12A  BI  = TP_SLOT2_CLKREQ_0_R_N
  J22  PR12B  BI  = FM_CPU0_PWR_BTN_N
  K1  PL14B  BI  = FM_SEC_MUX_R_SEL
  K2  PL14A  BI  = FM_SEC_MUX_OE_R_N
  K3  PL13D  BI  = E1S_0_P3V3_P12V_ADC_ALERT
  K4  PL13C  BI  = P12V_HSC_T_CRIT_R_N
  K5  PL13B  BI  = P12V_SCM_ADC_ALERT
  K6  PL12D  BI  = FAB_BMC_REV_ID2
  K7  PL12C  BI  = FAB_BMC_REV_ID1
  K8  VCCIO5_3  POWER  = P1V8_AUX
  K9  GND21  POWER  = GND
  K10  VCC1  POWER  = P3V3_AUX
  K11  VCC2  POWER  = P3V3_AUX
  K12  VCC3  POWER  = P3V3_AUX
  K13  VCC4  POWER  = P3V3_AUX
  K14  GND22  POWER  = GND
  K15  VCCIO1_3  POWER  = P1V8_AUX
  K16  PR13D  BI  = APML_CPU1_ALERT_R_N
  K17  PR13C  BI  = FM_P0_PCC0_R_N
  K18  PR13B  BI  = FM_P0_PCC1_R_N
  K19  PR13A  BI  = RST_RT_CPU1_P2_RESET_R2_N
  K20  PR12D  BI  = RST_RT_CPU1_P2_PERST_R2_N
  K21  GND23  POWER  = GND
  K22  PR16A  BI  = RST_RT_CPU0_P0_PERST_R2_N
  L1  \pl16a||pclkt4_0\  BI  = LED_HDD_ACTIVITY_B_PLD_N
  L2  GND24  POWER  = GND
  L3  PL16C  BI  = FM_THERMAL_ALERT_R_N
  L4  PL16D  BI  = SMB_BMC_GPU_EN
  L5  PL14D  BI  = PVDDCR_CPU1_P0_SMB_ALERT
  L6  PL14C  BI  = PVDDCR_CPU1_P1_SMB_ALERT
  L7  PL13A  BI  = PVDD11_S3_P0_PMALERT
  L8  VCCIO4_1  POWER  = P3V3_AUX
  L9  GND25  POWER  = GND
  L10  GND26  POWER  = GND
  L11  VCC5  POWER  = P3V3_AUX
  L12  VCC6  POWER  = P3V3_AUX
  L13  GND27  POWER  = GND
  L14  GND28  POWER  = GND
  L15  VCCIO1_4  POWER  = P1V8_AUX
  L16  PR14B  BI  = CPU1_SPD_HOST_CTRL_R1_N
  L17  PR14A  BI  = APML_CPU0_ALERT_R_N
  L18  GND29  POWER  = GND
  L19  PR14C  BI  = RST_RT_CPU1_P3_PERST_R2_N
  L20  PR14D  BI  = RST_RT_CPU1_P3_RESET_R2_N
  L21  PR16B  BI  = RST_RT_CPU0_P0_RESET_R2_N
  L22  PR16C  BI  = RST_RT_CPU0_P1_PERST_R2_N
  M1  PL17A  BI  = M2_0_P3V3_ADC_ALERT
  M2  \pl16b||pclkc4_0\  BI  = FM_SCM_PRSNT1_N
  M3  VCCIO4_3  POWER  = P3V3_AUX
  M4  GND30  POWER  = GND
  M5  PL17D  BI  = PVDDCR_CPU0_P1_PMALERT
  M6  PL17C  BI  = FM_PLD_OCP_SFF_AUX_PWR_R_EN
  M7  PL19D  BI  = FM_PLD_OCP_SFF_MAIN_PWR_EN_R
  M8  VCCIO4_2  POWER  = P3V3_AUX
  M9  GND31  POWER  = GND
  M10  GND32  POWER  = GND
  M11  VCC7  POWER  = P3V3_AUX
  M12  VCC8  POWER  = P3V3_AUX
  M13  GND33  POWER  = GND
  M14  GND34  POWER  = GND
  M15  VCCIO1_5  POWER  = P1V8_AUX
  M16  PR18A  BI  = PWRGD_P3V3_R2
  M17  PR16D  BI  = RST_RT_CPU0_P1_RESET_R2_N
  M18  VCCIO1_6  POWER  = P1V8_AUX
  M19  PR17D  BI  = SMB_CPU_5_R1_SDA
  M20  PR17C  BI  = SMB_CPU_5_R1_SCL
  M21  \pr17b||pclkc1_0\  BI  = FM_CPU0_SMERR_N
  M22  \pr17a||pclkt1_0\  BI  = FM_SMERR_LED_R_N
  N1  PL17B  BI  = PVDD11_S3_P1_PMALERT
  N2  PL18A  BI  = FM_CLKREQ_M2_1_N
  N3  PL18C  BI  = FM_CLR_CMOS
  N4  PL18D  BI  = PWRGD_OCP_SFF_PWR_GOOD
  N5  PL20B  BI  = FM_CPU0_SP5R1
  N6  PL20C  BI  = FM_CPU0_SP5R2
  N7  PL20D  BI  = P12V_HSC_TEMP_ALERT_R_N
  N8  VCCIO3_1  POWER  = P3V3_AUX
  N9  GND35  POWER  = GND
  N10  VCC9  POWER  = P3V3_AUX
  N11  VCC10  POWER  = P3V3_AUX
  N12  VCC11  POWER  = P3V3_AUX
  N13  VCC12  POWER  = P3V3_AUX
  N14  GND36  POWER  = GND
  N15  VCCIO1_7  POWER  = P1V8_AUX
  N16  PR18B  BI  = FM_CPU1_SMERR_N
  N17  PR18C  BI  = FM_ESPI_CPU0_ALERT_SEL
  N18  PR18D  BI  = RST_RT_CPU0_P2_PERST_R2_N
  N19  PR19D  BI  = PWRGD_P12V_MEM_R
  N20  PR19C  BI  = TP_PWRGD_P12V_FAN_DR_R
  N21  GND37  POWER  = GND
  N22  PR19A  BI  = BIOS_DEBUG_MODE_R
  P1  PL18B  BI  = OCP_V3_2_P3V3_P12V_ADC_ALERT
  P2  PL19A  BI  = FM_SMB_RST_E1S_0_N
  P3  PL19C  BI  = FM_CPU0_CORETYPE2
  P4  PL20A  BI  = FM_CPU1_CORETYPE0
